(kicad_pcb
	(version 20221018)
	(generator pcbnew)
	(general
    (thickness 1.518)
  )
	(paper "A4")
	(title_block
    (title "Kria K26 Devboard")
    (date "2024-03-26")
    (rev "1.2.5")
    (comment 1 "www.antmicro.com")
    (comment 2 "Antmicro Ltd.")
		(comment 9 "footprints 127-133 of 660")
	)
	(layers
    (0 "F.Cu" mixed)
    (1 "In1.Cu" power)
    (2 "In2.Cu" mixed)
    (3 "In3.Cu" power)
    (4 "In4.Cu" mixed)
    (5 "In5.Cu" power)
    (6 "In6.Cu" mixed)
    (31 "B.Cu" power)
    (32 "B.Adhes" user "B.Adhesive")
    (33 "F.Adhes" user "F.Adhesive")
    (34 "B.Paste" user)
    (35 "F.Paste" user)
    (36 "B.SilkS" user "B.Silkscreen")
    (37 "F.SilkS" user "F.Silkscreen")
    (38 "B.Mask" user)
    (39 "F.Mask" user)
    (40 "Dwgs.User" user "User.Drawings")
    (41 "Cmts.User" user "User.Comments")
    (42 "Eco1.User" user "User.Eco1")
    (43 "Eco2.User" user "User.Eco2")
    (44 "Edge.Cuts" user)
    (45 "Margin" user)
    (46 "B.CrtYd" user "B.Courtyard")
    (47 "F.CrtYd" user "F.Courtyard")
    (48 "B.Fab" user)
    (49 "F.Fab" user)
  )
	(footprint "kria-k26-devboard-footprints:VQFN-16-1EP_3x3mm_P0.5mm_EP1.68x1.68mm" (layer "F.Cu")
    (at 114.9 121.3)
    (property "Author" "Antmicro")
    (property "License" "Apache-2.0")
    (property "MPN" "NB3L202KMNTXG")
    (property "Manufacturer" "ON Semiconductor")
    (property "Sheetfile" "clock.kicad_sch")
    (property "Sheetname" "Clock distribution")
    (property "ki_description" "Fanout Buffer, 2 Outputs, 2.97V to 3.63 V, QFN-16, -40°C to 85°C")
    (property "ki_keywords" "SMT, CLOCK, IC")
    (attr smd)
    (fp_text reference "U7" (at -1.31 -1.96) (layer "F.SilkS")
        (effects (font (size 0.7 0.7) (thickness 0.15)) (justify left bottom))
    )
    (fp_text value "NB3L202KMN" (at 0 2.999) (layer "F.Fab") hide
        (effects (font (size 0.7 0.7) (thickness 0.15)) (justify left bottom))
    )
    (fp_text user "License: Apache-2.0" (at -1.901 7.4) (layer "F.Fab") hide
        (effects (font (size 0.7 0.7) (thickness 0.15)) (justify left bottom))
    )
    (fp_text user "${REFERENCE}" (at -1.901 4.998) (layer "F.Fab") hide
        (effects (font (size 0.7 0.7) (thickness 0.15)) (justify left bottom))
    )
    (fp_text user "Author: Antmicro" (at -1.901 6.2) (layer "F.Fab") hide
        (effects (font (size 0.7 0.7) (thickness 0.15)) (justify left bottom))
    )
    (fp_line (start -1.5 -1.5) (end -1.5 -0.951)
      (stroke (width 0.15) (type solid)) (layer "F.SilkS"))
    (fp_line (start -1.5 1.499) (end -1.5 0.95)
      (stroke (width 0.15) (type solid)) (layer "F.SilkS"))
    (fp_line (start -1.5 1.499) (end -0.951 1.499)
      (stroke (width 0.15) (type solid)) (layer "F.SilkS"))
    (fp_line (start -0.95 -1.501) (end -1.5 -1.5)
      (stroke (width 0.15) (type solid)) (layer "F.SilkS"))
    (fp_line (start 0.95 1.499) (end 1.499 1.499)
      (stroke (width 0.15) (type solid)) (layer "F.SilkS"))
    (fp_line (start 1.499 -1.5) (end 0.95 -1.5)
      (stroke (width 0.15) (type solid)) (layer "F.SilkS"))
    (fp_line (start 1.499 0.95) (end 1.499 1.499)
      (stroke (width 0.15) (type solid)) (layer "F.SilkS"))
    (fp_line (start 1.5 -0.95) (end 1.499 -1.5)
      (stroke (width 0.15) (type solid)) (layer "F.SilkS"))
    (fp_circle (center -1.75 -1.07071) (end -1.7 -1.02071)
      (stroke (width 0.15) (type solid)) (fill solid) (layer "F.SilkS"))
    (fp_rect (start -1.75 -1.75) (end 1.75 1.75)
      (stroke (width 0.05) (type solid)) (fill none) (layer "F.CrtYd"))
    (fp_line (start -1.5 -1.2) (end -1.5 1.499)
      (stroke (width 0.15) (type solid)) (layer "F.Fab"))
    (fp_line (start -1.5 -1.2) (end -1.2 -1.5)
      (stroke (width 0.15) (type solid)) (layer "F.Fab"))
    (fp_line (start -1.2 -1.5) (end 1.499 -1.5)
      (stroke (width 0.15) (type solid)) (layer "F.Fab"))
    (fp_line (start 1.499 1.499) (end -1.5 1.499)
      (stroke (width 0.15) (type solid)) (layer "F.Fab"))
    (fp_line (start 1.499 1.499) (end 1.499 -1.5)
      (stroke (width 0.15) (type solid)) (layer "F.Fab"))
    (pad "1" smd roundrect (at -1.401 -0.75) (size 0.6 0.25) (layers "F.Cu" "F.Paste" "F.Mask") (roundrect_rratio 0.2)
      (net 1 "GND") (pinfunction "GND") (pintype "power_in"))
    (pad "2" smd roundrect (at -1.401 -0.25) (size 0.6 0.25) (layers "F.Cu" "F.Paste" "F.Mask") (roundrect_rratio 0.2)
      (net 297 "/Clock distribution/CLK_100M_N") (pinfunction "CLK_{IN}+") (pintype "input"))
    (pad "3" smd roundrect (at -1.401 0.248) (size 0.6 0.25) (layers "F.Cu" "F.Paste" "F.Mask") (roundrect_rratio 0.2)
      (net 296 "/Clock distribution/CLK_100M_P") (pinfunction "CLK_{IN}-") (pintype "input"))
    (pad "4" smd roundrect (at -1.401 0.748) (size 0.6 0.25) (layers "F.Cu" "F.Paste" "F.Mask") (roundrect_rratio 0.2)
      (net 15 "PS_3V3") (pinfunction "VDD") (pintype "power_in"))
    (pad "5" smd roundrect (at -0.75 1.398 90) (size 0.6 0.25) (layers "F.Cu" "F.Paste" "F.Mask") (roundrect_rratio 0.2)
      (net 1 "GND") (pinfunction "GND_O") (pintype "passive"))
    (pad "6" smd roundrect (at -0.25 1.398 90) (size 0.6 0.25) (layers "F.Cu" "F.Paste" "F.Mask") (roundrect_rratio 0.2)
      (net 121 "/Clock distribution/GTR_REFCLK3_N") (pinfunction "DIF_{1}-") (pintype "output"))
    (pad "7" smd roundrect (at 0.248 1.398 90) (size 0.6 0.25) (layers "F.Cu" "F.Paste" "F.Mask") (roundrect_rratio 0.2)
      (net 122 "/Clock distribution/GTR_REFCLK3_P") (pinfunction "DIF_{1}+") (pintype "output"))
    (pad "8" smd roundrect (at 0.748 1.398 90) (size 0.6 0.25) (layers "F.Cu" "F.Paste" "F.Mask") (roundrect_rratio 0.2)
      (net 15 "PS_3V3") (pinfunction "VDD_O") (pintype "passive"))
    (pad "9" smd roundrect (at 1.398 0.748 180) (size 0.6 0.25) (layers "F.Cu" "F.Paste" "F.Mask") (roundrect_rratio 0.2)
      (net 1 "GND") (pinfunction "GND") (pintype "passive"))
    (pad "10" smd roundrect (at 1.398 0.248 180) (size 0.6 0.25) (layers "F.Cu" "F.Paste" "F.Mask") (roundrect_rratio 0.2)
      (net 642 "Net-(U7-I_{REF})") (pinfunction "I_{REF}") (pintype "input"))
    (pad "11" smd roundrect (at 1.398 -0.25 180) (size 0.6 0.25) (layers "F.Cu" "F.Paste" "F.Mask") (roundrect_rratio 0.2)
      (net 429 "Net-(Q3-C)") (pinfunction "~{OE0}") (pintype "input"))
    (pad "12" smd roundrect (at 1.398 -0.75 180) (size 0.6 0.25) (layers "F.Cu" "F.Paste" "F.Mask") (roundrect_rratio 0.2)
      (net 226 "/Clock distribution/~{M2_CLKREQ}") (pinfunction "~{OE1}") (pintype "input"))
    (pad "13" smd roundrect (at 0.748 -1.401 270) (size 0.6 0.25) (layers "F.Cu" "F.Paste" "F.Mask") (roundrect_rratio 0.2)
      (net 15 "PS_3V3") (pinfunction "VDD_O") (pintype "power_in"))
    (pad "14" smd roundrect (at 0.248 -1.401 270) (size 0.6 0.25) (layers "F.Cu" "F.Paste" "F.Mask") (roundrect_rratio 0.2)
      (net 107 "/Clock distribution/GTR_REFCLK3_C2M_P") (pinfunction "DIF_{0}+") (pintype "output"))
    (pad "15" smd roundrect (at -0.25 -1.401 270) (size 0.6 0.25) (layers "F.Cu" "F.Paste" "F.Mask") (roundrect_rratio 0.2)
      (net 108 "/Clock distribution/GTR_REFCLK3_C2M_N") (pinfunction "DIF_{0}-") (pintype "output"))
    (pad "16" smd roundrect (at -0.75 -1.401 270) (size 0.6 0.25) (layers "F.Cu" "F.Paste" "F.Mask") (roundrect_rratio 0.2)
      (net 1 "GND") (pinfunction "GND_O") (pintype "power_in"))
    (pad "17" smd roundrect (at 0 0) (size 1.55 1.55) (layers "F.Cu" "F.Paste" "F.Mask") (roundrect_rratio 0.2)
      (net 1 "GND") (pinfunction "EPAD") (pintype "power_in"))
  )
	(footprint "kria-k26-devboard-footprints:R_0402_1005Metric" (layer "F.Cu")
    (at 111.08 122.25 90)
    (descr "Resistor SMD 0402")
    (tags "resistor SMD 0402")
    (property "Author" "Antmicro")
    (property "License" "Apache-2.0")
    (property "MPN" "CR0402-FX-49R9GLF")
    (property "Manufacturer" "Bourns")
    (property "Sheetfile" "clock.kicad_sch")
    (property "Sheetname" "Clock distribution")
    (property "Tolerance" "1%")
    (property "Val" "49R9")
    (property "ki_description" "49R9 resistor in 0402 package with 1% tolerance")
    (attr smd)
    (fp_text reference "R20" (at -2.99 0.33 90) (layer "F.SilkS")
        (effects (font (size 0.7 0.7) (thickness 0.15)) (justify left bottom))
    )
    (fp_text value "R_49R9_0402" (at 0 1.4 90) (layer "F.Fab") hide
        (effects (font (size 0.7 0.7) (thickness 0.15)) (justify left bottom))
    )
    (fp_text user "License: Apache-2.0" (at -0.95 5.169 90) (layer "F.Fab") hide
        (effects (font (size 0.7 0.7) (thickness 0.15)) (justify left bottom))
    )
    (fp_text user "Author: Antmicro" (at -0.95 4.169 90) (layer "F.Fab") hide
        (effects (font (size 0.7 0.7) (thickness 0.15)) (justify left bottom))
    )
    (fp_text user "${REFERENCE}" (at -0.95 3.168 90) (layer "F.Fab") hide
        (effects (font (size 0.7 0.7) (thickness 0.15)) (justify left bottom))
    )
    (fp_rect (start -0.93 -0.47) (end 0.93 0.47)
      (stroke (width 0.05) (type solid)) (fill none) (layer "F.CrtYd"))
    (fp_rect (start -0.5 -0.25) (end 0.5 0.25)
      (stroke (width 0.15) (type solid)) (fill none) (layer "F.Fab"))
    (pad "1" smd roundrect (at -0.485 0 90) (size 0.59 0.64) (layers "F.Cu" "F.Paste" "F.Mask") (roundrect_rratio 0.25)
      (net 1 "GND") (pintype "passive"))
    (pad "2" smd roundrect (at 0.485 0 90) (size 0.59 0.64) (layers "F.Cu" "F.Paste" "F.Mask") (roundrect_rratio 0.25)
      (net 296 "/Clock distribution/CLK_100M_P") (pintype "passive"))
  )
	(footprint "kria-k26-devboard-footprints:R_0402_1005Metric" (layer "F.Cu")
    (at 111.08 120.35 -90)
    (descr "Resistor SMD 0402")
    (tags "resistor SMD 0402")
    (property "Author" "Antmicro")
    (property "License" "Apache-2.0")
    (property "MPN" "CR0402-FX-49R9GLF")
    (property "Manufacturer" "Bourns")
    (property "Sheetfile" "clock.kicad_sch")
    (property "Sheetname" "Clock distribution")
    (property "Tolerance" "1%")
    (property "Val" "49R9")
    (property "ki_description" "49R9 resistor in 0402 package with 1% tolerance")
    (attr smd)
    (fp_text reference "R21" (at 0.95 -1.28 -90) (layer "F.SilkS")
        (effects (font (size 0.7 0.7) (thickness 0.15)) (justify left bottom))
    )
    (fp_text value "R_49R9_0402" (at 0 1.4 -90) (layer "F.Fab") hide
        (effects (font (size 0.7 0.7) (thickness 0.15)) (justify left bottom))
    )
    (fp_text user "Author: Antmicro" (at -0.95 4.169 -90) (layer "F.Fab") hide
        (effects (font (size 0.7 0.7) (thickness 0.15)) (justify left bottom))
    )
    (fp_text user "${REFERENCE}" (at -0.95 3.168 -90) (layer "F.Fab") hide
        (effects (font (size 0.7 0.7) (thickness 0.15)) (justify left bottom))
    )
    (fp_text user "License: Apache-2.0" (at -0.95 5.169 -90) (layer "F.Fab") hide
        (effects (font (size 0.7 0.7) (thickness 0.15)) (justify left bottom))
    )
    (fp_rect (start -0.93 -0.47) (end 0.93 0.47)
      (stroke (width 0.05) (type solid)) (fill none) (layer "F.CrtYd"))
    (fp_rect (start -0.5 -0.25) (end 0.5 0.25)
      (stroke (width 0.15) (type solid)) (fill none) (layer "F.Fab"))
    (pad "1" smd roundrect (at -0.485 0 270) (size 0.59 0.64) (layers "F.Cu" "F.Paste" "F.Mask") (roundrect_rratio 0.25)
      (net 1 "GND") (pintype "passive"))
    (pad "2" smd roundrect (at 0.485 0 270) (size 0.59 0.64) (layers "F.Cu" "F.Paste" "F.Mask") (roundrect_rratio 0.25)
      (net 297 "/Clock distribution/CLK_100M_N") (pintype "passive"))
  )
	(footprint "kria-k26-devboard-footprints:Oscillator_SMD_Abracon_AX3_3.2x2.5x1mm" (layer "F.Cu")
    (at 109 120.7)
    (property "Author" "Antmicro")
    (property "License" "Apache-2.0")
    (property "MPN" "NX3241E0100.000000")
    (property "Manufacturer" "Diodes Incorporated")
    (property "Sheetfile" "clock.kicad_sch")
    (property "Sheetname" "Clock distribution")
    (property "Val" "100 MHz")
    (property "ki_description" "100 MHz XO (Standard) HCSL Oscillator 3.3V Enable/Disable 6-SMD, No Lead")
    (property "ki_keywords" "OSCILLATOR")
    (attr smd)
    (fp_text reference "Y1" (at 0.8 2.73) (layer "F.SilkS")
        (effects (font (size 0.7 0.7) (thickness 0.15)) (justify right bottom))
    )
    (fp_text value "Oscillator_100MHz_NX324" (at 0 2.8) (layer "F.Fab") hide
        (effects (font (size 0.7 0.7) (thickness 0.15)) (justify left bottom))
    )
    (fp_text user "Author: Antmicro" (at -1.6 5.3) (layer "F.Fab") hide
        (effects (font (size 0.7 0.7) (thickness 0.15)) (justify left bottom))
    )
    (fp_text user "${REFERENCE}" (at -1.6 4.1) (layer "F.Fab") hide
        (effects (font (size 0.7 0.7) (thickness 0.15)) (justify left bottom))
    )
    (fp_text user "License: Apache-2.0" (at -1.6 6.499) (layer "F.Fab") hide
        (effects (font (size 0.7 0.7) (thickness 0.15)) (justify left bottom))
    )
    (fp_line (start -1.5 -1.8) (end -1.5 -1.5)
      (stroke (width 0.12) (type solid)) (layer "F.SilkS"))
    (fp_line (start -1.5 1.5) (end -1.5 1.8)
      (stroke (width 0.12) (type solid)) (layer "F.SilkS"))
    (fp_line (start -1.5 1.8) (end 1.5 1.8)
      (stroke (width 0.12) (type solid)) (layer "F.SilkS"))
    (fp_line (start 1.5 -1.8) (end -1.5 -1.8)
      (stroke (width 0.12) (type solid)) (layer "F.SilkS"))
    (fp_line (start 1.5 -1.5) (end 1.5 -1.8)
      (stroke (width 0.12) (type solid)) (layer "F.SilkS"))
    (fp_line (start 1.5 1.8) (end 1.5 1.5)
      (stroke (width 0.12) (type solid)) (layer "F.SilkS"))
    (fp_circle (center -1.7 -1.9) (end -1.7 -1.85)
      (stroke (width 0.15) (type solid)) (fill solid) (layer "F.SilkS"))
    (fp_rect (start 1.6 -1.9) (end -1.6 1.9)
      (stroke (width 0.05) (type solid)) (fill none) (layer "F.CrtYd"))
    (fp_line (start -0.6 -1.6) (end -1.3 -0.9)
      (stroke (width 0.15) (type solid)) (layer "F.Fab"))
    (fp_rect (start 1.3 -1.601) (end -1.3 1.599)
      (stroke (width 0.15) (type solid)) (fill none) (layer "F.Fab"))
    (pad "1" smd rect (at -0.8 -1.199 270) (size 0.9 1.1) (layers "F.Cu" "F.Paste" "F.Mask")
      (net 185 "/Clock distribution/PS_CLK_EN") (pinfunction "EN") (pintype "input"))
    (pad "2" smd rect (at -0.8 0 270) (size 0.9 1.1) (layers "F.Cu" "F.Paste" "F.Mask")
      (net 796 "unconnected-(Y1-NC-Pad2)") (pinfunction "NC") (pintype "no_connect"))
    (pad "3" smd rect (at -0.8 1.199 270) (size 0.9 1.1) (layers "F.Cu" "F.Paste" "F.Mask")
      (net 1 "GND") (pinfunction "GND") (pintype "power_in"))
    (pad "4" smd rect (at 0.801 1.199 270) (size 0.9 1.1) (layers "F.Cu" "F.Paste" "F.Mask")
      (net 296 "/Clock distribution/CLK_100M_P") (pinfunction "OUT+") (pintype "output"))
    (pad "5" smd rect (at 0.801 0 270) (size 0.9 1.1) (layers "F.Cu" "F.Paste" "F.Mask")
      (net 297 "/Clock distribution/CLK_100M_N") (pinfunction "OUT-") (pintype "output"))
    (pad "6" smd rect (at 0.801 -1.199 270) (size 0.9 1.1) (layers "F.Cu" "F.Paste" "F.Mask")
      (net 15 "PS_3V3") (pinfunction "VCC") (pintype "power_in"))
  )
	(footprint "kria-k26-devboard-footprints:C_0402_1005Metric" (layer "F.Cu")
    (at 109.6 118.32 180)
    (descr "Capacitor SMD 0402")
    (tags "capacitor SMD 0402")
    (property "Author" "Antmicro")
    (property "Dielectric" "X5R")
    (property "License" "Apache-2.0")
    (property "MPN" "GRM155R61H104KE14D")
    (property "Manufacturer" "Murata")
    (property "Sheetfile" "clock.kicad_sch")
    (property "Sheetname" "Clock distribution")
    (property "Val" "100n")
    (property "Voltage" "50V")
    (property "ki_description" " ")
    (attr smd)
    (fp_text reference "C21" (at 1.13 0.88 180) (layer "F.SilkS")
        (effects (font (size 0.7 0.7) (thickness 0.15)) (justify left bottom))
    )
    (fp_text value "C_100n_0402" (at 0 1.4 180) (layer "F.Fab") hide
        (effects (font (size 0.7 0.7) (thickness 0.15)) (justify left bottom))
    )
    (fp_text user "Author: Antmicro" (at -0.932 4.17 180) (layer "F.Fab") hide
        (effects (font (size 0.7 0.7) (thickness 0.15)) (justify left bottom))
    )
    (fp_text user "${REFERENCE}" (at -0.932 3.168 180) (layer "F.Fab") hide
        (effects (font (size 0.7 0.7) (thickness 0.15)) (justify left bottom))
    )
    (fp_text user "License: Apache-2.0" (at -0.932 5.17 180) (layer "F.Fab") hide
        (effects (font (size 0.7 0.7) (thickness 0.15)) (justify left bottom))
    )
    (fp_rect (start -0.94 -0.47) (end 0.94 0.47)
      (stroke (width 0.05) (type solid)) (fill none) (layer "F.CrtYd"))
    (fp_rect (start -0.499 -0.249) (end 0.499 0.249)
      (stroke (width 0.15) (type solid)) (fill none) (layer "F.Fab"))
    (pad "1" smd roundrect (at -0.484 0 180) (size 0.59 0.64) (layers "F.Cu" "F.Paste" "F.Mask") (roundrect_rratio 0.25)
      (net 15 "PS_3V3") (pintype "passive"))
    (pad "2" smd roundrect (at 0.484 0 180) (size 0.59 0.64) (layers "F.Cu" "F.Paste" "F.Mask") (roundrect_rratio 0.25)
      (net 1 "GND") (pintype "passive"))
  )
	(footprint "kria-k26-devboard-footprints:C_0402_1005Metric" (layer "F.Cu")
    (at 116.9 118.8)
    (descr "Capacitor SMD 0402")
    (tags "capacitor SMD 0402")
    (property "Author" "Antmicro")
    (property "Dielectric" "X5R")
    (property "License" "Apache-2.0")
    (property "MPN" "GRM155R61H104KE14D")
    (property "Manufacturer" "Murata")
    (property "Sheetfile" "clock.kicad_sch")
    (property "Sheetname" "Clock distribution")
    (property "Val" "100n")
    (property "Voltage" "50V")
    (property "ki_description" " ")
    (attr smd)
    (fp_text reference "C26" (at -1.29 -0.57) (layer "F.SilkS")
        (effects (font (size 0.7 0.7) (thickness 0.15)) (justify left bottom))
    )
    (fp_text value "C_100n_0402" (at 0 1.4) (layer "F.Fab") hide
        (effects (font (size 0.7 0.7) (thickness 0.15)) (justify left bottom))
    )
    (fp_text user "License: Apache-2.0" (at -0.932 5.17) (layer "F.Fab") hide
        (effects (font (size 0.7 0.7) (thickness 0.15)) (justify left bottom))
    )
    (fp_text user "${REFERENCE}" (at -0.932 3.168) (layer "F.Fab") hide
        (effects (font (size 0.7 0.7) (thickness 0.15)) (justify left bottom))
    )
    (fp_text user "Author: Antmicro" (at -0.932 4.17) (layer "F.Fab") hide
        (effects (font (size 0.7 0.7) (thickness 0.15)) (justify left bottom))
    )
    (fp_rect (start -0.94 -0.47) (end 0.94 0.47)
      (stroke (width 0.05) (type solid)) (fill none) (layer "F.CrtYd"))
    (fp_rect (start -0.499 -0.249) (end 0.499 0.249)
      (stroke (width 0.15) (type solid)) (fill none) (layer "F.Fab"))
    (pad "1" smd roundrect (at -0.484 0) (size 0.59 0.64) (layers "F.Cu" "F.Paste" "F.Mask") (roundrect_rratio 0.25)
      (net 15 "PS_3V3") (pintype "passive"))
    (pad "2" smd roundrect (at 0.484 0) (size 0.59 0.64) (layers "F.Cu" "F.Paste" "F.Mask") (roundrect_rratio 0.25)
      (net 1 "GND") (pintype "passive"))
  )
	(footprint "kria-k26-devboard-footprints:C_0402_1005Metric" (layer "F.Cu")
    (at 112.61 123.05 -90)
    (descr "Capacitor SMD 0402")
    (tags "capacitor SMD 0402")
    (property "Author" "Antmicro")
    (property "Dielectric" "X5R")
    (property "License" "Apache-2.0")
    (property "MPN" "GRM155R61H104KE14D")
    (property "Manufacturer" "Murata")
    (property "Sheetfile" "clock.kicad_sch")
    (property "Sheetname" "Clock distribution")
    (property "Val" "100n")
    (property "Voltage" "50V")
    (property "ki_description" " ")
    (attr smd)
    (fp_text reference "C23" (at 3.01 -0.39 -90) (layer "F.SilkS")
        (effects (font (size 0.7 0.7) (thickness 0.15)) (justify left bottom))
    )
    (fp_text value "C_100n_0402" (at 0 1.4 -90) (layer "F.Fab") hide
        (effects (font (size 0.7 0.7) (thickness 0.15)) (justify left bottom))
    )
    (fp_text user "License: Apache-2.0" (at -0.932 5.17 -90) (layer "F.Fab") hide
        (effects (font (size 0.7 0.7) (thickness 0.15)) (justify left bottom))
    )
    (fp_text user "Author: Antmicro" (at -0.932 4.17 -90) (layer "F.Fab") hide
        (effects (font (size 0.7 0.7) (thickness 0.15)) (justify left bottom))
    )
    (fp_text user "${REFERENCE}" (at -0.932 3.168 -90) (layer "F.Fab") hide
        (effects (font (size 0.7 0.7) (thickness 0.15)) (justify left bottom))
    )
    (fp_rect (start -0.94 -0.47) (end 0.94 0.47)
      (stroke (width 0.05) (type solid)) (fill none) (layer "F.CrtYd"))
    (fp_rect (start -0.499 -0.249) (end 0.499 0.249)
      (stroke (width 0.15) (type solid)) (fill none) (layer "F.Fab"))
    (pad "1" smd roundrect (at -0.484 0 270) (size 0.59 0.64) (layers "F.Cu" "F.Paste" "F.Mask") (roundrect_rratio 0.25)
      (net 15 "PS_3V3") (pintype "passive"))
    (pad "2" smd roundrect (at 0.484 0 270) (size 0.59 0.64) (layers "F.Cu" "F.Paste" "F.Mask") (roundrect_rratio 0.25)
      (net 1 "GND") (pintype "passive"))
  )
)
